(kicad_pcb
	(version 20260206)
	(generator "pcbnew")
	(generator_version "10.0")
	(general
		(thickness 1.6)
		(legacy_teardrops no)
	)
	(paper "A4")
	(title_block
		(title "peb — Lightning_PEB_BRD.brd")
		(comment 1 "Lightning (Wiwynn / Facebook NVMe JBOF) / footprints 754-761 of 2563")
	)
	(layers
		(0 "F.Cu" signal "TOP")
		(4 "In1.Cu" signal "L2GND")
		(6 "In2.Cu" signal "L3")
		(8 "In3.Cu" signal "L4VCC")
		(10 "In4.Cu" signal "L5VCC")
		(12 "In5.Cu" signal "L6")
		(14 "In6.Cu" signal "L7GND")
		(2 "B.Cu" signal "BOTTOM")
		(9 "F.Adhes" user "F.Adhesive")
		(11 "B.Adhes" user "B.Adhesive")
		(13 "F.Paste" user "Package Geometry/Pastemask Top")
		(15 "B.Paste" user "Package Geometry/Pastemask Bottom")
		(5 "F.SilkS" user "Ref Des/Silkscreen Top")
		(7 "B.SilkS" user "Ref Des/Silkscreen Bottom")
		(1 "F.Mask" user "Board Geometry/Soldermask Top")
		(3 "B.Mask" user "Board Geometry/Soldermask Bottom")
		(17 "Dwgs.User" user "User.Drawings")
		(19 "Cmts.User" user "User.Comments")
		(21 "Eco1.User" user "User.Eco1")
		(23 "Eco2.User" user "User.Eco2")
		(25 "Edge.Cuts" user "Board Geometry/Outline")
		(27 "Margin" user)
		(31 "F.CrtYd" user "Package Geometry/Place Bound Top")
		(29 "B.CrtYd" user "Package Geometry/Place Bound Bottom")
		(35 "F.Fab" user "Ref Des/Assembly Top")
		(33 "B.Fab" user "Ref Des/Assembly Bottom")
	)
	(footprint ""
		(layer "F.Cu")
		(at 322.453 -99.568)
		(property "Reference" "R593"
			(at 0 0 0)
			(layer "F.SilkS")
			(hide yes)
			(effects
				(font
					(size 1.27 1.27)
				)
			)
		)
		(property "Value" "10KR2F-2-GP"
			(at 0.064008 -3.993896 0)
			(unlocked yes)
			(layer "F.Fab")
			(hide yes)
			(effects
				(font
					(size 1.016 1.016)
					(thickness 0.1524)
				)
			)
		)
		(property "Device Type" "R402H16"
			(at 0.064008 -5.517896 0)
			(unlocked yes)
			(layer "F.Fab")
			(hide yes)
			(effects
				(font
					(size 1.016 1.016)
					(thickness 0.1524)
				)
			)
		)
		(duplicate_pad_numbers_are_jumpers no)
		(fp_line
			(start -0.508 -0.9398)
			(end -0.508 0.9398)
			(stroke
				(width 0.1524)
				(type default)
			)
			(layer "F.SilkS")
		)
		(fp_line
			(start 0.508 -0.9398)
			(end -0.508 -0.9398)
			(stroke
				(width 0.1524)
				(type default)
			)
			(layer "F.SilkS")
		)
		(fp_rect
			(start -0.508 0.9398)
			(end 0.508 -0.9398)
			(stroke
				(width 0)
				(type default)
			)
			(fill no)
			(layer "F.CrtYd")
		)
		(fp_rect
			(start -0.508 0.9398)
			(end 0.508 -0.9398)
			(stroke
				(width 0)
				(type default)
			)
			(fill no)
			(layer "F.Fab")
		)
		(pad "1" smd custom
			(at 0 -0.4445)
			(size 0.1397 0.1397)
			(layers "F.Cu" "F.Mask" "F.Paste")
			(net "P3V3_STBY")
			(options
				(clearance outline)
				(anchor circle)
			)
			(primitives
				(gr_poly
					(pts
						(arc
							(start -0.1778 -0.2794)
							(mid -0.249642 -0.249642)
							(end -0.2794 -0.1778)
						)
						(arc
							(start -0.2794 0.1778)
							(mid -0.249642 0.249642)
							(end -0.1778 0.2794)
						)
						(arc
							(start 0.1778 0.2794)
							(mid 0.249642 0.249642)
							(end 0.2794 0.1778)
						)
						(arc
							(start 0.2794 -0.1778)
							(mid 0.249642 -0.249642)
							(end 0.1778 -0.2794)
						)
					)
					(width 0)
					(fill yes)
				)
			)
		)
		(pad "2" smd custom
			(at 0 0.4445)
			(size 0.1397 0.1397)
			(layers "F.Cu" "F.Mask" "F.Paste")
			(net "IOEXP_PMC1_AD0")
			(options
				(clearance outline)
				(anchor circle)
			)
			(primitives
				(gr_poly
					(pts
						(arc
							(start -0.1778 -0.2794)
							(mid -0.249642 -0.249642)
							(end -0.2794 -0.1778)
						)
						(arc
							(start -0.2794 0.1778)
							(mid -0.249642 0.249642)
							(end -0.1778 0.2794)
						)
						(arc
							(start 0.1778 0.2794)
							(mid 0.249642 0.249642)
							(end 0.2794 0.1778)
						)
						(arc
							(start 0.2794 -0.1778)
							(mid 0.249642 -0.249642)
							(end 0.1778 -0.2794)
						)
					)
					(width 0)
					(fill yes)
				)
			)
		)
	)
	(footprint ""
		(layer "F.Cu")
		(at 57.3786 -26.3144 180)
		(property "Reference" "R736"
			(at 0 0 180)
			(layer "F.SilkS")
			(hide yes)
			(effects
				(font
					(size 1.27 1.27)
				)
			)
		)
		(property "Value" "0R2J-2-GP"
			(at 0.064008 -3.993896 180)
			(unlocked yes)
			(layer "F.Fab")
			(hide yes)
			(effects
				(font
					(size 1.016 1.016)
					(thickness 0.1524)
				)
			)
		)
		(property "Device Type" "R402H16"
			(at 0.064008 -5.517896 180)
			(unlocked yes)
			(layer "F.Fab")
			(hide yes)
			(effects
				(font
					(size 1.016 1.016)
					(thickness 0.1524)
				)
			)
		)
		(duplicate_pad_numbers_are_jumpers no)
		(fp_line
			(start 0.508 -0.9398)
			(end -0.508 -0.9398)
			(stroke
				(width 0.1524)
				(type default)
			)
			(layer "F.SilkS")
		)
		(fp_line
			(start -0.508 -0.9398)
			(end -0.508 0.9398)
			(stroke
				(width 0.1524)
				(type default)
			)
			(layer "F.SilkS")
		)
		(fp_rect
			(start -0.508 0.9398)
			(end 0.508 -0.9398)
			(stroke
				(width 0)
				(type default)
			)
			(fill no)
			(layer "F.CrtYd")
		)
		(fp_rect
			(start -0.508 0.9398)
			(end 0.508 -0.9398)
			(stroke
				(width 0)
				(type default)
			)
			(fill no)
			(layer "F.Fab")
		)
		(pad "1" smd custom
			(at 0 -0.4445 180)
			(size 0.1397 0.1397)
			(layers "F.Cu" "F.Mask" "F.Paste")
			(net "IPMB_DAT")
			(options
				(clearance outline)
				(anchor circle)
			)
			(primitives
				(gr_poly
					(pts
						(arc
							(start -0.1778 -0.2794)
							(mid -0.249642 -0.249642)
							(end -0.2794 -0.1778)
						)
						(arc
							(start -0.2794 0.1778)
							(mid -0.249642 0.249642)
							(end -0.1778 0.2794)
						)
						(arc
							(start 0.1778 0.2794)
							(mid 0.249642 0.249642)
							(end 0.2794 0.1778)
						)
						(arc
							(start 0.2794 -0.1778)
							(mid 0.249642 -0.249642)
							(end 0.1778 -0.2794)
						)
					)
					(width 0)
					(fill yes)
				)
			)
		)
		(pad "2" smd custom
			(at 0 0.4445 180)
			(size 0.1397 0.1397)
			(layers "F.Cu" "F.Mask" "F.Paste")
			(net "BMC_I2C14_MINI8_SDA_S")
			(options
				(clearance outline)
				(anchor circle)
			)
			(primitives
				(gr_poly
					(pts
						(arc
							(start -0.1778 -0.2794)
							(mid -0.249642 -0.249642)
							(end -0.2794 -0.1778)
						)
						(arc
							(start -0.2794 0.1778)
							(mid -0.249642 0.249642)
							(end -0.1778 0.2794)
						)
						(arc
							(start 0.1778 0.2794)
							(mid 0.249642 0.249642)
							(end 0.2794 0.1778)
						)
						(arc
							(start 0.2794 -0.1778)
							(mid 0.249642 -0.249642)
							(end 0.1778 -0.2794)
						)
					)
					(width 0)
					(fill yes)
				)
			)
		)
	)
	(footprint ""
		(layer "F.Cu")
		(at 119.80164 -36.324032 90)
		(property "Reference" "R621"
			(at 0 0 90)
			(layer "F.SilkS")
			(hide yes)
			(effects
				(font
					(size 1.27 1.27)
				)
			)
		)
		(property "Value" "0R2J-2-GP"
			(at 0.064008 -3.993896 90)
			(unlocked yes)
			(layer "F.Fab")
			(hide yes)
			(effects
				(font
					(size 1.016 1.016)
					(thickness 0.1524)
				)
			)
		)
		(property "Device Type" "R402H16"
			(at 0.064008 -5.51815 90)
			(unlocked yes)
			(layer "F.Fab")
			(hide yes)
			(effects
				(font
					(size 1.016 1.016)
					(thickness 0.1524)
				)
			)
		)
		(duplicate_pad_numbers_are_jumpers no)
		(fp_line
			(start 0.508 -0.940054)
			(end -0.508 -0.9398)
			(stroke
				(width 0.1524)
				(type default)
			)
			(layer "F.SilkS")
		)
		(fp_line
			(start -0.508 -0.9398)
			(end -0.508 0.939546)
			(stroke
				(width 0.1524)
				(type default)
			)
			(layer "F.SilkS")
		)
		(fp_rect
			(start -0.508 0.939546)
			(end 0.508 -0.940054)
			(stroke
				(width 0)
				(type default)
			)
			(fill no)
			(layer "F.CrtYd")
		)
		(fp_rect
			(start -0.508 0.939546)
			(end 0.508 -0.940054)
			(stroke
				(width 0)
				(type default)
			)
			(fill no)
			(layer "F.Fab")
		)
		(pad "1" smd custom
			(at 0 -0.4445 90)
			(size 0.1397 0.1397)
			(layers "F.Cu" "F.Mask" "F.Paste")
			(net "UPLINK2_R")
			(options
				(clearance outline)
				(anchor circle)
			)
			(primitives
				(gr_poly
					(pts
						(arc
							(start -0.1778 -0.2794)
							(mid -0.249642 -0.249642)
							(end -0.2794 -0.1778)
						)
						(arc
							(start -0.2794 0.1778)
							(mid -0.249642 0.249642)
							(end -0.1778 0.2794)
						)
						(arc
							(start 0.1778 0.2794)
							(mid 0.249642 0.249642)
							(end 0.2794 0.1778)
						)
						(arc
							(start 0.2794 -0.1778)
							(mid 0.249642 -0.249642)
							(end 0.1778 -0.2794)
						)
					)
					(width 0)
					(fill yes)
				)
			)
		)
		(pad "2" smd custom
			(at 0 0.4445 90)
			(size 0.1397 0.1397)
			(layers "F.Cu" "F.Mask" "F.Paste")
			(net "UPLINK2")
			(options
				(clearance outline)
				(anchor circle)
			)
			(primitives
				(gr_poly
					(pts
						(arc
							(start -0.1778 -0.2794)
							(mid -0.249642 -0.249642)
							(end -0.2794 -0.1778)
						)
						(arc
							(start -0.2794 0.1778)
							(mid -0.249642 0.249642)
							(end -0.1778 0.2794)
						)
						(arc
							(start 0.1778 0.2794)
							(mid 0.249642 0.249642)
							(end 0.2794 0.1778)
						)
						(arc
							(start 0.2794 -0.1778)
							(mid 0.249642 -0.249642)
							(end 0.1778 -0.2794)
						)
					)
					(width 0)
					(fill yes)
				)
			)
		)
	)
	(footprint ""
		(layer "F.Cu")
		(at 149.008084 -212.420454 180)
		(property "Reference" "C313"
			(at 0 0 180)
			(layer "F.SilkS")
			(hide yes)
			(effects
				(font
					(size 1.27 1.27)
				)
			)
		)
		(property "Value" "SCD22U10V2KX-1GP"
			(at 1.1811 -2.7051 180)
			(unlocked yes)
			(layer "F.Fab")
			(hide yes)
			(effects
				(font
					(size 1.016 1.016)
					(thickness 0.1524)
				)
			)
		)
		(property "Device Type" "C402H22"
			(at 1.1811 -4.2291 180)
			(unlocked yes)
			(layer "F.Fab")
			(hide yes)
			(effects
				(font
					(size 1.016 1.016)
					(thickness 0.1524)
				)
			)
		)
		(duplicate_pad_numbers_are_jumpers no)
		(fp_rect
			(start -0.4318 0.9525)
			(end 0.4318 -0.9525)
			(stroke
				(width 0)
				(type default)
			)
			(fill no)
			(layer "F.CrtYd")
		)
		(fp_rect
			(start -0.4318 0.9525)
			(end 0.4318 -0.9525)
			(stroke
				(width 0)
				(type default)
			)
			(fill no)
			(layer "F.Fab")
		)
		(pad "1" smd custom
			(at 0 -0.4445 180)
			(size 0.1524 0.1524)
			(layers "F.Cu" "F.Mask" "F.Paste")
			(net "PCIE_TX_CAP_N56")
			(options
				(clearance outline)
				(anchor circle)
			)
			(primitives
				(gr_poly
					(pts
						(arc
							(start 0.3048 -0.2032)
							(mid 0.275042 -0.275042)
							(end 0.2032 -0.3048)
						)
						(arc
							(start -0.2032 -0.3048)
							(mid -0.275042 -0.275042)
							(end -0.3048 -0.2032)
						)
						(arc
							(start -0.3048 0.2032)
							(mid -0.275042 0.275042)
							(end -0.2032 0.3048)
						)
						(arc
							(start 0.2032 0.3048)
							(mid 0.275042 0.275042)
							(end 0.3048 0.2032)
						)
					)
					(width 0)
					(fill yes)
				)
			)
		)
		(pad "2" smd custom
			(at 0 0.4445 180)
			(size 0.1524 0.1524)
			(layers "F.Cu" "F.Mask" "F.Paste")
			(net "PCIE_TX_N56")
			(options
				(clearance outline)
				(anchor circle)
			)
			(primitives
				(gr_poly
					(pts
						(arc
							(start 0.3048 -0.2032)
							(mid 0.275042 -0.275042)
							(end 0.2032 -0.3048)
						)
						(arc
							(start -0.2032 -0.3048)
							(mid -0.275042 -0.275042)
							(end -0.3048 -0.2032)
						)
						(arc
							(start -0.3048 0.2032)
							(mid -0.275042 0.275042)
							(end -0.2032 0.3048)
						)
						(arc
							(start 0.2032 0.3048)
							(mid 0.275042 0.275042)
							(end 0.3048 0.2032)
						)
					)
					(width 0)
					(fill yes)
				)
			)
		)
	)
	(footprint ""
		(layer "F.Cu")
		(at 53.721 -131.445 -90)
		(property "Reference" "C190"
			(at 0 0 270)
			(layer "F.SilkS")
			(hide yes)
			(effects
				(font
					(size 1.27 1.27)
				)
			)
		)
		(property "Value" "SCD1U16V2KX-3GP"
			(at 1.1811 -2.7051 270)
			(unlocked yes)
			(layer "F.Fab")
			(hide yes)
			(effects
				(font
					(size 1.016 1.016)
					(thickness 0.1524)
				)
			)
		)
		(property "Device Type" "C402H22"
			(at 1.1811 -4.2291 270)
			(unlocked yes)
			(layer "F.Fab")
			(hide yes)
			(effects
				(font
					(size 1.016 1.016)
					(thickness 0.1524)
				)
			)
		)
		(duplicate_pad_numbers_are_jumpers no)
		(fp_rect
			(start -0.4318 0.9525)
			(end 0.4318 -0.9525)
			(stroke
				(width 0)
				(type default)
			)
			(fill no)
			(layer "F.CrtYd")
		)
		(fp_rect
			(start -0.4318 0.9525)
			(end 0.4318 -0.9525)
			(stroke
				(width 0)
				(type default)
			)
			(fill no)
			(layer "F.Fab")
		)
		(pad "1" smd custom
			(at 0 -0.4445 270)
			(size 0.1524 0.1524)
			(layers "F.Cu" "F.Mask" "F.Paste")
			(net "GND")
			(options
				(clearance outline)
				(anchor circle)
			)
			(primitives
				(gr_poly
					(pts
						(arc
							(start 0.3048 -0.2032)
							(mid 0.275042 -0.275042)
							(end 0.2032 -0.3048)
						)
						(arc
							(start -0.2032 -0.3048)
							(mid -0.275042 -0.275042)
							(end -0.3048 -0.2032)
						)
						(arc
							(start -0.3048 0.2032)
							(mid -0.275042 0.275042)
							(end -0.2032 0.3048)
						)
						(arc
							(start 0.2032 0.3048)
							(mid 0.275042 0.275042)
							(end 0.3048 0.2032)
						)
					)
					(width 0)
					(fill yes)
				)
			)
		)
		(pad "2" smd custom
			(at 0 0.4445 270)
			(size 0.1524 0.1524)
			(layers "F.Cu" "F.Mask" "F.Paste")
			(net "ADCVREFFN")
			(options
				(clearance outline)
				(anchor circle)
			)
			(primitives
				(gr_poly
					(pts
						(arc
							(start 0.3048 -0.2032)
							(mid 0.275042 -0.275042)
							(end 0.2032 -0.3048)
						)
						(arc
							(start -0.2032 -0.3048)
							(mid -0.275042 -0.275042)
							(end -0.3048 -0.2032)
						)
						(arc
							(start -0.3048 0.2032)
							(mid -0.275042 0.275042)
							(end -0.2032 0.3048)
						)
						(arc
							(start 0.2032 0.3048)
							(mid 0.275042 0.275042)
							(end 0.3048 0.2032)
						)
					)
					(width 0)
					(fill yes)
				)
			)
		)
	)
	(footprint ""
		(layer "F.Cu")
		(at 13.5128 -120.904 180)
		(property "Reference" "R601"
			(at 0 0 180)
			(layer "F.SilkS")
			(hide yes)
			(effects
				(font
					(size 1.27 1.27)
				)
			)
		)
		(property "Value" "4K7R2F-GP"
			(at 0.064008 -3.993896 180)
			(unlocked yes)
			(layer "F.Fab")
			(hide yes)
			(effects
				(font
					(size 1.016 1.016)
					(thickness 0.1524)
				)
			)
		)
		(property "Device Type" "R402H16"
			(at 0.064008 -5.517896 180)
			(unlocked yes)
			(layer "F.Fab")
			(hide yes)
			(effects
				(font
					(size 1.016 1.016)
					(thickness 0.1524)
				)
			)
		)
		(duplicate_pad_numbers_are_jumpers no)
		(fp_line
			(start 0.508 -0.9398)
			(end -0.508 -0.9398)
			(stroke
				(width 0.1524)
				(type default)
			)
			(layer "F.SilkS")
		)
		(fp_line
			(start -0.508 -0.9398)
			(end -0.508 0.9398)
			(stroke
				(width 0.1524)
				(type default)
			)
			(layer "F.SilkS")
		)
		(fp_rect
			(start -0.508 0.9398)
			(end 0.508 -0.9398)
			(stroke
				(width 0)
				(type default)
			)
			(fill no)
			(layer "F.CrtYd")
		)
		(fp_rect
			(start -0.508 0.9398)
			(end 0.508 -0.9398)
			(stroke
				(width 0)
				(type default)
			)
			(fill no)
			(layer "F.Fab")
		)
		(pad "1" smd custom
			(at 0 -0.4445 180)
			(size 0.1397 0.1397)
			(layers "F.Cu" "F.Mask" "F.Paste")
			(net "BMC_I2C1_MINI1_SCL_S")
			(options
				(clearance outline)
				(anchor circle)
			)
			(primitives
				(gr_poly
					(pts
						(arc
							(start -0.1778 -0.2794)
							(mid -0.249642 -0.249642)
							(end -0.2794 -0.1778)
						)
						(arc
							(start -0.2794 0.1778)
							(mid -0.249642 0.249642)
							(end -0.1778 0.2794)
						)
						(arc
							(start 0.1778 0.2794)
							(mid 0.249642 0.249642)
							(end 0.2794 0.1778)
						)
						(arc
							(start 0.2794 -0.1778)
							(mid 0.249642 -0.249642)
							(end 0.1778 -0.2794)
						)
					)
					(width 0)
					(fill yes)
				)
			)
		)
		(pad "2" smd custom
			(at 0 0.4445 180)
			(size 0.1397 0.1397)
			(layers "F.Cu" "F.Mask" "F.Paste")
			(net "P3V3_STBY")
			(options
				(clearance outline)
				(anchor circle)
			)
			(primitives
				(gr_poly
					(pts
						(arc
							(start -0.1778 -0.2794)
							(mid -0.249642 -0.249642)
							(end -0.2794 -0.1778)
						)
						(arc
							(start -0.2794 0.1778)
							(mid -0.249642 0.249642)
							(end -0.1778 0.2794)
						)
						(arc
							(start 0.1778 0.2794)
							(mid 0.249642 0.249642)
							(end 0.2794 0.1778)
						)
						(arc
							(start 0.2794 -0.1778)
							(mid 0.249642 -0.249642)
							(end 0.1778 -0.2794)
						)
					)
					(width 0)
					(fill yes)
				)
			)
		)
	)
	(footprint ""
		(layer "F.Cu")
		(at 65.4812 -154.0256 90)
		(property "Reference" "PC70"
			(at 0 0 90)
			(layer "F.SilkS")
			(hide yes)
			(effects
				(font
					(size 1.27 1.27)
				)
			)
		)
		(property "Value" "SC4D7U16V5KX-1-GP"
			(at -0.0762 -6.1214 90)
			(unlocked yes)
			(layer "F.Fab")
			(hide yes)
			(effects
				(font
					(size 1.016 1.016)
					(thickness 0.1524)
				)
			)
		)
		(property "Device Type" "C805H56"
			(at -0.0762 -8.1534 90)
			(unlocked yes)
			(layer "F.Fab")
			(hide yes)
			(effects
				(font
					(size 1.016 1.016)
					(thickness 0.1524)
				)
			)
		)
		(duplicate_pad_numbers_are_jumpers no)
		(fp_line
			(start 0.635 0)
			(end -0.635 0)
			(stroke
				(width 0.508)
				(type default)
			)
			(layer "F.SilkS")
		)
		(fp_rect
			(start -0.9652 1.778)
			(end 0.9652 -1.778)
			(stroke
				(width 0)
				(type default)
			)
			(fill no)
			(layer "F.CrtYd")
		)
		(fp_poly
			(pts
				(xy -0.9652 -1.778) (xy 0.9652 -1.778) (xy 0.9652 1.778) (xy -0.9652 1.778)
			)
			(stroke
				(width 0)
				(type default)
			)
			(fill no)
			(layer "F.Fab")
		)
		(pad "1" smd rect
			(at 0 -0.9652 90)
			(size 1.397 1.143)
			(layers "F.Cu" "F.Mask" "F.Paste")
			(net "P1V53_PWR")
		)
		(pad "2" smd rect
			(at 0 0.9652 90)
			(size 1.397 1.143)
			(layers "F.Cu" "F.Mask" "F.Paste")
			(net "GND")
		)
	)
	(footprint ""
		(layer "F.Cu")
		(at 6.4262 -188.1886)
		(property "Reference" "PR9007"
			(at 0 0 0)
			(layer "F.SilkS")
			(hide yes)
			(effects
				(font
					(size 1.27 1.27)
				)
			)
		)
		(property "Value" "0R2J-2-GP"
			(at 0.064008 -3.993896 0)
			(unlocked yes)
			(layer "F.Fab")
			(hide yes)
			(effects
				(font
					(size 1.016 1.016)
					(thickness 0.1524)
				)
			)
		)
		(property "Device Type" "R402H16"
			(at 0.064008 -5.517896 0)
			(unlocked yes)
			(layer "F.Fab")
			(hide yes)
			(effects
				(font
					(size 1.016 1.016)
					(thickness 0.1524)
				)
			)
		)
		(duplicate_pad_numbers_are_jumpers no)
		(fp_line
			(start -0.508 -0.9398)
			(end -0.508 0.9398)
			(stroke
				(width 0.1524)
				(type default)
			)
			(layer "F.SilkS")
		)
		(fp_line
			(start 0.508 -0.9398)
			(end -0.508 -0.9398)
			(stroke
				(width 0.1524)
				(type default)
			)
			(layer "F.SilkS")
		)
		(fp_rect
			(start -0.508 0.9398)
			(end 0.508 -0.9398)
			(stroke
				(width 0)
				(type default)
			)
			(fill no)
			(layer "F.CrtYd")
		)
		(fp_rect
			(start -0.508 0.9398)
			(end 0.508 -0.9398)
			(stroke
				(width 0)
				(type default)
			)
			(fill no)
			(layer "F.Fab")
		)
		(pad "1" smd custom
			(at 0 -0.4445)
			(size 0.1397 0.1397)
			(layers "F.Cu" "F.Mask" "F.Paste")
			(net "MB0_HS_ENABLE")
			(options
				(clearance outline)
				(anchor circle)
			)
			(primitives
				(gr_poly
					(pts
						(arc
							(start -0.1778 -0.2794)
							(mid -0.249642 -0.249642)
							(end -0.2794 -0.1778)
						)
						(arc
							(start -0.2794 0.1778)
							(mid -0.249642 0.249642)
							(end -0.1778 0.2794)
						)
						(arc
							(start 0.1778 0.2794)
							(mid 0.249642 0.249642)
							(end 0.2794 0.1778)
						)
						(arc
							(start 0.2794 -0.1778)
							(mid 0.249642 -0.249642)
							(end 0.1778 -0.2794)
						)
					)
					(width 0)
					(fill yes)
				)
			)
		)
		(pad "2" smd custom
			(at 0 0.4445)
			(size 0.1397 0.1397)
			(layers "F.Cu" "F.Mask" "F.Paste")
			(net "Q95_D")
			(options
				(clearance outline)
				(anchor circle)
			)
			(primitives
				(gr_poly
					(pts
						(arc
							(start -0.1778 -0.2794)
							(mid -0.249642 -0.249642)
							(end -0.2794 -0.1778)
						)
						(arc
							(start -0.2794 0.1778)
							(mid -0.249642 0.249642)
							(end -0.1778 0.2794)
						)
						(arc
							(start 0.1778 0.2794)
							(mid 0.249642 0.249642)
							(end 0.2794 0.1778)
						)
						(arc
							(start 0.2794 -0.1778)
							(mid 0.249642 -0.249642)
							(end 0.1778 -0.2794)
						)
					)
					(width 0)
					(fill yes)
				)
			)
		)
	)
)
